FILE_TYPE = CONNECTIVITY;
{Allegro Design Entry HDL 16.6-p007 (v16-6-112F) 10/10/2012}
"PAGE_NUMBER" = 148;
0"NC";
1"VCC_D_3V3\g";
2"P1V2_AUX_BMC\g";
3"VCC_VA_3V3\g";
4"VCC_D_PLL_3V3\g";
5"P3V3_STBY\g";
6"P1V15_AUX_BMC\g";
7"P3V3_STBY\g";
8"PVCCIO_CPU0\g";
9"GND\g";
10"VCC_ADCAV3V3\g";
11"VCC_A_1V1\g";
12"GND\g";
13"P3V3_STBY\g";
14"VCC_DACAV3V3\g";
15"P3V3_USB2A_ALG\g";
16"VCC_PA_3V3\g";
17"VCC_D_3V3\g";
18"FM_SLPS3_N";
19"FM_SLPS4_N";
20"FM_CPU1_FIVR_FAULT_LVT3_R_N";
21"VCCBAT_TW12";
22"FM_CPU1_FIVR_FAULT_LVT3_N";
%"W_VCC_CIRCLE"
"1","(-5875,3625)","0","w_power","I10";
;
CDS_LIB"w_power"
CDS_LMAN_SYM_OUTLINE"-100,100,100,-100"
BODY_TYPE"PLUMBING"
HDL_POWER"VCC_D_3V3";
"VCC_CIRCLE \B"1;
%"W_VCC_CIRCLE"
"1","(-5675,2875)","0","w_power","I14";
;
BODY_TYPE"PLUMBING"
CDS_LMAN_SYM_OUTLINE"-100,100,100,-100"
CDS_LIB"w_power"
HDL_POWER"P1V2_AUX_BMC";
"VCC_CIRCLE \B"2;
%"W_VCC_CIRCLE"
"1","(-6300,3925)","0","w_power","I15";
;
BODY_TYPE"PLUMBING"
CDS_LMAN_SYM_OUTLINE"-100,100,100,-100"
CDS_LIB"w_power"
HDL_POWER"VCC_VA_3V3";
"VCC_CIRCLE \B"3;
%"RES"
"1","(-6550,3825)","0","mstr_discrete","I16";
;
CDS_SEC"1"
$SEC"1"
CDS_LOCATION"R25W59"
CDS_LIB"mstr_discrete"
BOM_COST"MIO_USB"
ROOM"USB"
PART_NUMBER"G21497-005"
WATTAGE"1/16W"
TOLERANCE"5%"
LOCATION"R25W59"
VALUE"0.0"
MATERIAL"CHIP"
PACK_TYPE"0402";
"B"
$PN"2"21;
"A"
$PN"1"5;
%"W_VCC_CIRCLE"
"1","(-6625,3550)","0","w_power","I17";
;
CDS_LMAN_SYM_OUTLINE"-100,100,100,-100"
CDS_LIB"w_power"
BODY_TYPE"PLUMBING"
HDL_POWER"VCC_D_PLL_3V3";
"VCC_CIRCLE \B"4;
%"P3V3_STBY"
"1","(-6900,4050)","0","mstr_symbols","I18";
;
VOLTAGE"3.3V"
CDS_LIB"mstr_symbols"
SIZE"1B"
BODY_TYPE"PLUMBING"
HDL_POWER"P3V3_STBY";
"G\NAC"5;
%"W_VCC_CIRCLE"
"1","(-6225,2150)","0","w_power","I19";
;
BODY_TYPE"PLUMBING"
CDS_LIB"w_power"
CDS_LMAN_SYM_OUTLINE"-100,100,100,-100"
HDL_POWER"P1V15_AUX_BMC";
"VCC_CIRCLE \B"6;
%"P3V3_STBY"
"1","(-2250,4625)","0","mstr_symbols","I2";
;
HDL_POWER"P3V3_STBY"
BODY_TYPE"PLUMBING"
SIZE"1B"
VOLTAGE"3.3V"
CDS_LIB"mstr_symbols";
"G\NAC"7;
%"CAP_A"
"1","(-6925,2100)","0","dev_discrete","I20";
;
CDS_LOCATION"C1T21"
BOM_COST"SM_CONTROLLER"
CDS_LIB"dev_discrete"
CDS_SEC"1"
SEC_TYPE"0402V"
SEC"1"
ROOM"BMC"
LOCATION"C1T21"
PACK_TYPE"0402V"
MATERIAL"X6S"
PART_NUMBER"D97712-004"
VOLTAGE"6.3V"
TOLERANCE"10%"
VALUE"1.0UF";
"B"
$PN"2"9;
"A"
$PN"1"8;
%"PVCCIO_CPU0"
"1","(-6925,2375)","0","mstr_symbols","I21";
;
CDS_LIB"mstr_symbols"
VOLTAGE"1.1V"
BODY_TYPE"PLUMBING"
HDL_POWER"PVCCIO_CPU0";
"G\NAC"8;
%"GND"
"1","(-6925,1850)","0","mstr_symbols","I22";
;
HDL_POWER"GND"
BODY_TYPE"PLUMBING"
VOLTAGE"0.0V"
SIZE"1B"
CDS_LIB"mstr_symbols";
"A\NAC"9;
%"RES"
"1","(-5900,2475)","0","mstr_discrete","I23";
;
CDS_LOCATION"R25W75"
PART_NUMBER"G21796-074"
MATERIAL"CHIP"
CDS_LIB"mstr_discrete"
ROOM"BMC"
BOM_COST"SM_CONTROLLER"
SEC_TYPE"0402"
SEC"1"
CDS_SEC"1"
WATTAGE"1/16W"
PACK_TYPE"0402"
VALUE"33.2"
LOCATION"R25W75"
TOLERANCE"1%";
"B"
$PN"2"20;
"A"
$PN"1"22;
%"W_VCC_CIRCLE"
"1","(-5350,4375)","0","w_power","I26";
;
CDS_LIB"w_power"
CDS_LMAN_SYM_OUTLINE"-100,100,100,-100"
BODY_TYPE"PLUMBING"
HDL_POWER"VCC_ADCAV3V3";
"VCC_CIRCLE \B"10;
%"W_VCC_CIRCLE"
"1","(-5300,2025)","0","w_power","I27";
;
BODY_TYPE"PLUMBING"
CDS_LMAN_SYM_OUTLINE"-100,100,100,-100"
CDS_LIB"w_power"
HDL_POWER"VCC_A_1V1";
"VCC_CIRCLE \B"11;
%"AST2520A1-GP-GP"
"7","(-3600,2575)","0","w_hdl","I28";
;
CDS_SEC"7"
$SEC"7"
CDS_LOCATION"U25W4"
CDS_LIB"w_hdl"
PART_NUMBER"071.2520A.M001"
PACK_TYPE"ASIC2-GB1"
CDS_LMAN_SYM_OUTLINE"-850,2100,850,-2100"
VALUE"AST2520A1-GP-GP"
$LOCATION"U25W4";
"GND0"
$PN"A1"12;
"GND1"
$PN"A22"12;
"GND2"
$PN"AA11"12;
"GND3"
$PN"AA13"12;
"GND6"
$PN"AA9"12;
"GND8"
$PN"AB22"12;
"GND7"
$PN"AB1"12;
"GND5"
$PN"AA7"12;
"GND4"
$PN"AA15"12;
"GND11"
$PN"F16"12;
"GND12"
$PN"G19"12;
"GND13"
$PN"G6"12;
"GND10"
$PN"E8"12;
"GND9"
$PN"C6"12;
"GND16"
$PN"J11"12;
"GND17"
$PN"J12"12;
"GND18"
$PN"J13"12;
"GND15"
$PN"J10"12;
"GND14"
$PN"H6"12;
"GND19"
$PN"J14"12;
"GND21"
$PN"J22"12;
"GND22"
$PN"J5"12;
"GND23"
$PN"J9"12;
"GND20"
$PN"J21"12;
"GND24"
$PN"K10"12;
"GND26"
$PN"K12"12;
"GND28"
$PN"K14"12;
"GND27"
$PN"K13"12;
"GND25"
$PN"K11"12;
"GND29"
$PN"K16"12;
"GND31"
$PN"L10"12;
"GND32"
$PN"L11"12;
"GND33"
$PN"L12"12;
"GND34"
$PN"L13"12;
"GND30"
$PN"K9"12;
"GND36"
$PN"L9"12;
"GND37"
$PN"M1"12;
"GND38"
$PN"M10"12;
"GND39"
$PN"M11"12;
"GND35"
$PN"L14"12;
"GND42"
$PN"M14"12;
"GND43"
$PN"M16"12;
"GND44"
$PN"M17"12;
"GND41"
$PN"M13"12;
"GND40"
$PN"M12"12;
"GND47"
$PN"M4"12;
"GND48"
$PN"M5"12;
"GND49"
$PN"M6"12;
"GND46"
$PN"M3"12;
"GND45"
$PN"M2"12;
"GND52"
$PN"N10"12;
"GND53"
$PN"N11"12;
"GND54"
$PN"N12"12;
"GND51"
$PN"M9"12;
"GND50"
$PN"M7"12;
"GND57"
$PN"N9"12;
"GND58"
$PN"T16"12;
"GND59"
$PN"T6"12;
"GND56"
$PN"N14"12;
"GND55"
$PN"N13"12;
"GND62"
$PN"U6"12;
"GND63"
$PN"V10"12;
"GND64"
$PN"V12"12;
"GND61"
$PN"U11"12;
"GND60"
$PN"T7"12;
"GND65"
$PN"V14"12;
"GND66"
$PN"V16"12;
"GND67"
$PN"V8"12;
"R1VDD1"
$PN"F11"13;
"R1VDD0"
$PN"F10"13;
"R2VDD1"
$PN"F8"13;
"R2VDD0"
$PN"F7"13;
"ADCAV33"
$PN"J6"10;
"DACDV33"
$PN"K5"14;
"USB2AV33"
$PN"C7"15;
"BATVDD"
$PN"E4"21;
"PEAV33"
$PN"L16"17;
"VPLLAV331"
$PN"H7"3;
"VPLLAV330"
$PN"J7"3;
"PLLAV331"
$PN"W17"16;
"PLLAV330"
$PN"Y17"16;
"PV33D14"
$PN"T15"1;
"PV33D13"
$PN"T11"4;
"PV33D12"
$PN"R6"1;
"PV33D11"
$PN"R17"1;
"PV33D10"
$PN"P6"1;
"PV33D9"
$PN"P17"1;
"PV33D8"
$PN"N6"1;
"PV33D7"
$PN"N17"1;
"PV33D6"
$PN"K7"1;
"PV33D5"
$PN"H17"1;
"PV33D4"
$PN"G16"1;
"PV33D3"
$PN"F15"1;
"PV33D2"
$PN"F14"1;
"PV33D1"
$PN"F13"1;
"MVDD3"
$PN"T14"2;
"MVDD2"
$PN"T13"2;
"MVDD1"
$PN"T12"2;
"MVDD0"
$PN"T10"2;
"PECIVDD"
$PN"AA17"8;
"PLLDV11"
$PN"V17"6;
"PEAV11"
$PN"L17"6;
"VPLLAV111"
$PN"L6"11;
"VPLLAV110"
$PN"L5"11;
"IV11D24"
$PN"R7"6;
"IV11D23"
$PN"R16"6;
"IV11D22"
$PN"P9"6;
"IV11D21"
$PN"P7"6;
"IV11D20"
$PN"P16"6;
"IV11D19"
$PN"P14"6;
"IV11D18"
$PN"P13"6;
"IV11D17"
$PN"P12"6;
"IV11D16"
$PN"P11"6;
"IV11D15"
$PN"P10"6;
"IV11D14"
$PN"N7"6;
"IV11D13"
$PN"N16"6;
"IV11D12"
$PN"L7"6;
"IV11D11"
$PN"J16"6;
"IV11D10"
$PN"H16"6;
"IV11D9"
$PN"G9"6;
"IV11D8"
$PN"G8"6;
"IV11D7"
$PN"G7"6;
"IV11D6"
$PN"G15"6;
"IV11D5"
$PN"G14"6;
"IV11D4"
$PN"G13"6;
"IV11D3"
$PN"G12"6;
"IV11D2"
$PN"G11"6;
"IV11D1"
$PN"G10"6;
"IV11D0"
$PN"F6"6;
"GPIOY0_SIOS3# \B"
$PN"R22"18;
"GPIOY1_SIOS5# \B"
$PN"R21"19;
"GPIOY2_SIOPWREQ# \B"
$PN"P22"20;
"MVDD4"
$PN"T8"2;
"PV33D0"
$PN"F12"1;
"DACAV33"
$PN"K6"14;
"GND68"
$PN"E5"12;
"LPVDD0"
$PN"J17"7;
"LPVDD1"
$PN"K17"7;
%"GND"
"1","(-2375,475)","0","mstr_symbols","I3";
;
CDS_LIB"mstr_symbols"
HDL_POWER"GND"
SIZE"1B"
BODY_TYPE"PLUMBING"
VOLTAGE"0.0V";
"A\NAC"12;
%"P3V3_STBY"
"1","(-5075,4775)","0","mstr_symbols","I4";
;
CDS_LIB"mstr_symbols"
HDL_POWER"P3V3_STBY"
BODY_TYPE"PLUMBING"
SIZE"1B"
VOLTAGE"3.3V";
"G\NAC"13;
%"W_VCC_CIRCLE"
"1","(-6025,4275)","0","w_power","I6";
;
BODY_TYPE"PLUMBING"
CDS_LMAN_SYM_OUTLINE"-100,100,100,-100"
CDS_LIB"w_power"
HDL_POWER"VCC_DACAV3V3";
"VCC_CIRCLE \B"14;
%"W_VCC_CIRCLE"
"1","(-6400,4175)","0","w_power","I7";
;
BODY_TYPE"PLUMBING"
CDS_LMAN_SYM_OUTLINE"-100,100,100,-100"
CDS_LIB"w_power"
HDL_POWER"P3V3_USB2A_ALG";
"VCC_CIRCLE \B"15;
%"W_VCC_CIRCLE"
"1","(-5025,3700)","0","w_power","I8";
;
BODY_TYPE"PLUMBING"
CDS_LMAN_SYM_OUTLINE"-100,100,100,-100"
CDS_LIB"w_power"
HDL_POWER"VCC_PA_3V3";
"VCC_CIRCLE \B"16;
%"W_VCC_CIRCLE"
"1","(-5400,3975)","0","w_power","I9";
;
CDS_LIB"w_power"
CDS_LMAN_SYM_OUTLINE"-100,100,100,-100"
BODY_TYPE"PLUMBING"
HDL_POWER"VCC_D_3V3";
"VCC_CIRCLE \B"17;
END.
